(kicad_pcb
	(version 20260206)
	(generator "pcbnew")
	(generator_version "10.0")
	(general
		(thickness 1.6)
		(legacy_teardrops no)
	)
	(paper "A4")
	(title_block
		(title "Wiwynn_Tioga_Pass_MB.brd")
		(comment 1 "Tioga Pass / footprints 4671-4677 of 4770")
	)
	(layers
		(0 "F.Cu" signal "TOP")
		(4 "In1.Cu" signal "L2GND")
		(6 "In2.Cu" signal "L3")
		(8 "In3.Cu" signal "L4GND")
		(10 "In4.Cu" signal "L5")
		(12 "In5.Cu" signal "L6GND")
		(14 "In6.Cu" signal "L7VCC")
		(16 "In7.Cu" signal "L8VCC")
		(18 "In8.Cu" signal "L9GND")
		(20 "In9.Cu" signal "L10")
		(22 "In10.Cu" signal "L11GND")
		(24 "In11.Cu" signal "L12")
		(26 "In12.Cu" signal "L13GND")
		(2 "B.Cu" signal "BOTTOM")
		(9 "F.Adhes" user "F.Adhesive")
		(11 "B.Adhes" user "B.Adhesive")
		(13 "F.Paste" user "Package Geometry/Pastemask Top")
		(15 "B.Paste" user "Package Geometry/Pastemask Bottom")
		(5 "F.SilkS" user "Ref Des/Silkscreen Top")
		(7 "B.SilkS" user "Ref Des/Silkscreen Bottom")
		(1 "F.Mask" user "Board Geometry/Soldermask Top")
		(3 "B.Mask" user "Board Geometry/Soldermask Bottom")
		(17 "Dwgs.User" user "User.Drawings")
		(19 "Cmts.User" user "User.Comments")
		(21 "Eco1.User" user "User.Eco1")
		(23 "Eco2.User" user "User.Eco2")
		(25 "Edge.Cuts" user "Board Geometry/Outline")
		(27 "Margin" user)
		(31 "F.CrtYd" user "Package Geometry/Place Bound Top")
		(29 "B.CrtYd" user "Package Geometry/Place Bound Bottom")
		(35 "F.Fab" user "Ref Des/Assembly Top")
		(33 "B.Fab" user "Ref Des/Assembly Bottom")
	)
	(footprint ""
		(layer "B.Cu")
		(at 376.344688 -77.096366 180)
		(property "Reference" "C3P52"
			(at 0 0 0)
			(layer "B.SilkS")
			(hide yes)
			(effects
				(font
					(size 1.27 1.27)
				)
				(justify mirror)
			)
		)
		(property "Value" ""
			(at 0 0 0)
			(layer "B.Fab")
			(effects
				(font
					(size 1.27 1.27)
				)
				(justify mirror)
			)
		)
		(duplicate_pad_numbers_are_jumpers no)
		(fp_rect
			(start 0.2794 0.9144)
			(end -0.2794 -0.1143)
			(stroke
				(width 0)
				(type default)
			)
			(fill no)
			(layer "B.CrtYd")
		)
		(fp_line
			(start 0.2794 0.9144)
			(end 0.2794 -0.1143)
			(stroke
				(width 0.1)
				(type default)
			)
			(layer "B.Fab")
		)
		(fp_line
			(start 0.2794 -0.1143)
			(end -0.2794 -0.1143)
			(stroke
				(width 0.1)
				(type default)
			)
			(layer "B.Fab")
		)
		(fp_line
			(start -0.2794 0.9144)
			(end 0.2794 0.9144)
			(stroke
				(width 0.1)
				(type default)
			)
			(layer "B.Fab")
		)
		(fp_line
			(start -0.2794 -0.1143)
			(end -0.2794 0.9144)
			(stroke
				(width 0.1)
				(type default)
			)
			(layer "B.Fab")
		)
		(pad "1" smd custom
			(at 0 0 90)
			(size 0.10414 0.10414)
			(layers "B.Cu" "B.Mask" "B.Paste")
			(net "P3V3_STBY")
			(options
				(clearance outline)
				(anchor circle)
			)
			(primitives
				(gr_poly
					(pts
						(xy -0.20828 -0.08636) (xy -0.20828 0.08636) (xy -0.08636 0.20828) (xy 0.086614 0.20828) (xy 0.20828 0.086614)
						(xy 0.20828 -0.08636) (xy 0.08636 -0.20828) (xy -0.08636 -0.20828)
					)
					(width 0)
					(fill yes)
				)
			)
		)
		(pad "2" smd custom
			(at 0 0.8001 90)
			(size 0.10414 0.10414)
			(layers "B.Cu" "B.Mask" "B.Paste")
			(net "GND")
			(options
				(clearance outline)
				(anchor circle)
			)
			(primitives
				(gr_poly
					(pts
						(xy -0.20828 -0.08636) (xy -0.20828 0.08636) (xy -0.08636 0.20828) (xy 0.086614 0.20828) (xy 0.20828 0.086614)
						(xy 0.20828 -0.08636) (xy 0.08636 -0.20828) (xy -0.08636 -0.20828)
					)
					(width 0)
					(fill yes)
				)
			)
		)
		(zone
			(layer "B.Cu")
			(hatch none 0.5)
			(connect_pads
				(clearance 0)
			)
			(min_thickness 0.25)
			(keepout
				(tracks not_allowed)
				(vias allowed)
				(pads allowed)
				(copperpour not_allowed)
				(footprints allowed)
			)
			(placement
				(enabled no)
				(sheetname "")
			)
			(fill
				(thermal_gap 0.5)
				(thermal_bridge_width 0.5)
				(island_removal_mode 0)
			)
			(polygon
				(pts
					(xy 376.257058 -77.305916) (xy 376.257058 -77.686916) (xy 376.432318 -77.686916) (xy 376.432572 -77.305916)
				)
			)
		)
		(zone
			(layer "B.Cu")
			(hatch none 0.5)
			(connect_pads
				(clearance 0)
			)
			(min_thickness 0.25)
			(keepout
				(tracks allowed)
				(vias not_allowed)
				(pads allowed)
				(copperpour not_allowed)
				(footprints allowed)
			)
			(placement
				(enabled no)
				(sheetname "")
			)
			(fill
				(thermal_gap 0.5)
				(thermal_bridge_width 0.5)
				(island_removal_mode 0)
			)
			(polygon
				(pts
					(xy 376.257058 -77.305916) (xy 376.257058 -77.686916) (xy 376.432318 -77.686916) (xy 376.432572 -77.305916)
				)
			)
		)
	)
	(footprint ""
		(layer "B.Cu")
		(at 461.658208 -132.842254 90)
		(property "Reference" "R1M3"
			(at 0 0 90)
			(layer "B.SilkS")
			(hide yes)
			(effects
				(font
					(size 1.27 1.27)
				)
				(justify mirror)
			)
		)
		(property "Value" ""
			(at 0 0 90)
			(layer "B.Fab")
			(effects
				(font
					(size 1.27 1.27)
				)
				(justify mirror)
			)
		)
		(duplicate_pad_numbers_are_jumpers no)
		(fp_poly
			(pts
				(xy 0.2794 -0.1016) (xy -0.2794 -0.1016) (xy -0.2794 0.9906) (xy 0.2794 0.9906)
			)
			(stroke
				(width 0)
				(type default)
			)
			(fill no)
			(layer "B.CrtYd")
		)
		(fp_line
			(start 0.2794 -0.1016)
			(end 0.2794 0.9906)
			(stroke
				(width 0.1)
				(type default)
			)
			(layer "B.Fab")
		)
		(fp_line
			(start -0.2794 -0.1016)
			(end 0.2794 -0.1016)
			(stroke
				(width 0.1)
				(type default)
			)
			(layer "B.Fab")
		)
		(fp_line
			(start 0.2794 0.9906)
			(end -0.2794 0.9906)
			(stroke
				(width 0.1)
				(type default)
			)
			(layer "B.Fab")
		)
		(fp_line
			(start -0.2794 0.9906)
			(end -0.2794 -0.1016)
			(stroke
				(width 0.1)
				(type default)
			)
			(layer "B.Fab")
		)
		(pad "1" smd rect
			(at 0 0 270)
			(size 0.508 0.508)
			(layers "B.Cu" "B.Mask" "B.Paste")
			(net "PVCCIO_CPU0")
		)
		(pad "2" smd rect
			(at 0 0.889 270)
			(size 0.508 0.508)
			(layers "B.Cu" "B.Mask" "B.Paste")
			(net "XDP_CPU_PRDY_N")
		)
		(zone
			(layer "B.Cu")
			(hatch none 0.5)
			(connect_pads
				(clearance 0)
			)
			(min_thickness 0.25)
			(keepout
				(tracks allowed)
				(vias not_allowed)
				(pads allowed)
				(copperpour not_allowed)
				(footprints allowed)
			)
			(placement
				(enabled no)
				(sheetname "")
			)
			(fill
				(thermal_gap 0.5)
				(thermal_bridge_width 0.5)
				(island_removal_mode 0)
			)
			(polygon
				(pts
					(xy 461.912208 -133.096254) (xy 461.912208 -132.588254) (xy 462.293208 -132.588254) (xy 462.293208 -133.096254)
				)
			)
		)
		(zone
			(layer "B.Cu")
			(hatch none 0.5)
			(connect_pads
				(clearance 0)
			)
			(min_thickness 0.25)
			(keepout
				(tracks not_allowed)
				(vias allowed)
				(pads allowed)
				(copperpour not_allowed)
				(footprints allowed)
			)
			(placement
				(enabled no)
				(sheetname "")
			)
			(fill
				(thermal_gap 0.5)
				(thermal_bridge_width 0.5)
				(island_removal_mode 0)
			)
			(polygon
				(pts
					(xy 462.293208 -133.096254) (xy 462.293208 -132.588254) (xy 461.912208 -132.588254) (xy 461.912208 -133.096254)
				)
			)
		)
	)
	(footprint ""
		(layer "B.Cu")
		(at 479.9965 -44.323 90)
		(property "Reference" "C1R29"
			(at 0 0 90)
			(layer "B.SilkS")
			(hide yes)
			(effects
				(font
					(size 1.27 1.27)
				)
				(justify mirror)
			)
		)
		(property "Value" ""
			(at 0 0 90)
			(layer "B.Fab")
			(effects
				(font
					(size 1.27 1.27)
				)
				(justify mirror)
			)
		)
		(duplicate_pad_numbers_are_jumpers no)
		(fp_poly
			(pts
				(xy -0.3048 -0.1016) (xy -0.3048 0.9906) (xy 0.3048 0.9906) (xy 0.3048 -0.1016)
			)
			(stroke
				(width 0)
				(type default)
			)
			(fill no)
			(layer "B.CrtYd")
		)
		(fp_line
			(start 0.3048 -0.1016)
			(end 0.3048 0.9906)
			(stroke
				(width 0.1)
				(type default)
			)
			(layer "B.Fab")
		)
		(fp_line
			(start -0.3048 -0.1016)
			(end 0.3048 -0.1016)
			(stroke
				(width 0.1)
				(type default)
			)
			(layer "B.Fab")
		)
		(fp_line
			(start 0.3048 0.9906)
			(end -0.3048 0.9906)
			(stroke
				(width 0.1)
				(type default)
			)
			(layer "B.Fab")
		)
		(fp_line
			(start -0.3048 0.9906)
			(end -0.3048 -0.1016)
			(stroke
				(width 0.1)
				(type default)
			)
			(layer "B.Fab")
		)
		(pad "1" smd rect
			(at 0 0 270)
			(size 0.508 0.508)
			(layers "B.Cu" "B.Mask" "B.Paste")
			(net "P1V5_LAN")
		)
		(pad "2" smd rect
			(at 0 0.889 270)
			(size 0.508 0.508)
			(layers "B.Cu" "B.Mask" "B.Paste")
			(net "GND")
		)
		(zone
			(layer "B.Cu")
			(hatch none 0.5)
			(connect_pads
				(clearance 0)
			)
			(min_thickness 0.25)
			(keepout
				(tracks allowed)
				(vias not_allowed)
				(pads allowed)
				(copperpour not_allowed)
				(footprints allowed)
			)
			(placement
				(enabled no)
				(sheetname "")
			)
			(fill
				(thermal_gap 0.5)
				(thermal_bridge_width 0.5)
				(island_removal_mode 0)
			)
			(polygon
				(pts
					(xy 480.2505 -44.577) (xy 480.2505 -44.069) (xy 480.6315 -44.069) (xy 480.6315 -44.577)
				)
			)
		)
		(zone
			(layer "B.Cu")
			(hatch none 0.5)
			(connect_pads
				(clearance 0)
			)
			(min_thickness 0.25)
			(keepout
				(tracks not_allowed)
				(vias allowed)
				(pads allowed)
				(copperpour not_allowed)
				(footprints allowed)
			)
			(placement
				(enabled no)
				(sheetname "")
			)
			(fill
				(thermal_gap 0.5)
				(thermal_bridge_width 0.5)
				(island_removal_mode 0)
			)
			(polygon
				(pts
					(xy 480.6315 -44.577) (xy 480.6315 -44.069) (xy 480.2505 -44.069) (xy 480.2505 -44.577)
				)
			)
		)
	)
	(footprint ""
		(layer "B.Cu")
		(at 406.8064 2.332228)
		(property "Reference" "U8G3"
			(at -2.667 -1.29667 180)
			(unlocked yes)
			(layer "B.SilkS")
			(effects
				(font
					(size 0.7874 0.5842)
					(thickness 0.1524)
				)
				(justify left mirror)
			)
		)
		(property "Value" ""
			(at 0 0 0)
			(layer "B.Fab")
			(effects
				(font
					(size 1.27 1.27)
				)
				(justify mirror)
			)
		)
		(duplicate_pad_numbers_are_jumpers no)
		(fp_circle
			(center 0.92964 -0.05588)
			(end 1.05664 -0.05588)
			(stroke
				(width 0.254)
				(type default)
			)
			(fill no)
			(layer "B.SilkS")
		)
		(fp_poly
			(pts
				(xy -0.21463 -0.450088) (xy -1.56337 -0.450088) (xy -1.56337 1.75006) (xy -0.21463 1.75006)
			)
			(stroke
				(width 0)
				(type default)
			)
			(fill no)
			(layer "B.CrtYd")
		)
		(fp_line
			(start -1.56337 -0.450088)
			(end -1.56337 1.75006)
			(stroke
				(width 0.1)
				(type default)
			)
			(layer "B.Fab")
		)
		(fp_line
			(start -1.56337 1.75006)
			(end -0.21463 1.75006)
			(stroke
				(width 0.1)
				(type default)
			)
			(layer "B.Fab")
		)
		(fp_line
			(start -0.21463 -0.450088)
			(end -1.56337 -0.450088)
			(stroke
				(width 0.1)
				(type default)
			)
			(layer "B.Fab")
		)
		(fp_line
			(start -0.21463 1.75006)
			(end -0.21463 -0.450088)
			(stroke
				(width 0.1)
				(type default)
			)
			(layer "B.Fab")
		)
		(fp_circle
			(center 0.4699 -0.8382)
			(end 0.5969 -0.8382)
			(stroke
				(width 0.254)
				(type default)
			)
			(fill no)
			(layer "B.Fab")
		)
		(pad "1" smd rect
			(at 0 0 180)
			(size 1.016 0.381)
			(layers "B.Cu" "B.Mask" "B.Paste")
			(net "Net_6468")
		)
		(pad "2" smd rect
			(at 0 0.649986 180)
			(size 1.016 0.381)
			(layers "B.Cu" "B.Mask" "B.Paste")
			(net "FAN_PWM_OUT_SYS1")
		)
		(pad "3" smd rect
			(at 0 1.299972 180)
			(size 1.016 0.381)
			(layers "B.Cu" "B.Mask" "B.Paste")
			(net "GND")
		)
		(pad "4" smd rect
			(at -1.778 1.299972 180)
			(size 1.016 0.381)
			(layers "B.Cu" "B.Mask" "B.Paste")
			(net "FAN_PWM_OUT_SYS1_BUF")
		)
		(pad "5" smd rect
			(at -1.778 0 180)
			(size 1.016 0.381)
			(layers "B.Cu" "B.Mask" "B.Paste")
			(net "P3V3_STBY")
		)
	)
	(footprint ""
		(layer "B.Cu")
		(at 0.762 -144.8562 90)
		(property "Reference" "R9L4"
			(at 0 0 90)
			(layer "B.SilkS")
			(hide yes)
			(effects
				(font
					(size 1.27 1.27)
				)
				(justify mirror)
			)
		)
		(property "Value" ""
			(at 0 0 90)
			(layer "B.Fab")
			(effects
				(font
					(size 1.27 1.27)
				)
				(justify mirror)
			)
		)
		(duplicate_pad_numbers_are_jumpers no)
		(fp_rect
			(start 0.2794 -0.1016)
			(end -0.2794 0.9906)
			(stroke
				(width 0)
				(type default)
			)
			(fill no)
			(layer "B.CrtYd")
		)
		(fp_line
			(start 0.2794 -0.1016)
			(end 0.2794 0.9906)
			(stroke
				(width 0.1)
				(type default)
			)
			(layer "B.Fab")
		)
		(fp_line
			(start -0.2794 -0.1016)
			(end 0.2794 -0.1016)
			(stroke
				(width 0.1)
				(type default)
			)
			(layer "B.Fab")
		)
		(fp_line
			(start 0.2794 0.9906)
			(end -0.2794 0.9906)
			(stroke
				(width 0.1)
				(type default)
			)
			(layer "B.Fab")
		)
		(fp_line
			(start -0.2794 0.9906)
			(end -0.2794 -0.1016)
			(stroke
				(width 0.1)
				(type default)
			)
			(layer "B.Fab")
		)
		(pad "1" smd rect
			(at 0 0 270)
			(size 0.508 0.508)
			(layers "B.Cu" "B.Mask" "B.Paste")
			(net "VR_PVDDQ_KLM_PH2_VCIN")
		)
		(pad "2" smd rect
			(at 0 0.889 270)
			(size 0.508 0.508)
			(layers "B.Cu" "B.Mask" "B.Paste")
			(net "P5V_STBY")
		)
		(zone
			(layer "B.Cu")
			(hatch none 0.5)
			(connect_pads
				(clearance 0)
			)
			(min_thickness 0.25)
			(keepout
				(tracks not_allowed)
				(vias allowed)
				(pads allowed)
				(copperpour not_allowed)
				(footprints allowed)
			)
			(placement
				(enabled no)
				(sheetname "")
			)
			(fill
				(thermal_gap 0.5)
				(thermal_bridge_width 0.5)
				(island_removal_mode 0)
			)
			(polygon
				(pts
					(xy 1.016 -145.1102) (xy 1.016 -144.6022) (xy 1.397 -144.6022) (xy 1.397 -145.1102)
				)
			)
		)
		(zone
			(layer "B.Cu")
			(hatch none 0.5)
			(connect_pads
				(clearance 0)
			)
			(min_thickness 0.25)
			(keepout
				(tracks allowed)
				(vias not_allowed)
				(pads allowed)
				(copperpour not_allowed)
				(footprints allowed)
			)
			(placement
				(enabled no)
				(sheetname "")
			)
			(fill
				(thermal_gap 0.5)
				(thermal_bridge_width 0.5)
				(island_removal_mode 0)
			)
			(polygon
				(pts
					(xy 1.016 -145.1102) (xy 1.016 -144.6022) (xy 1.397 -144.6022) (xy 1.397 -145.1102)
				)
			)
		)
	)
	(footprint ""
		(layer "B.Cu")
		(at 167.386 -87.757)
		(property "Reference" "R6P6"
			(at 0 0 0)
			(layer "B.SilkS")
			(hide yes)
			(effects
				(font
					(size 1.27 1.27)
				)
				(justify mirror)
			)
		)
		(property "Value" ""
			(at 0 0 0)
			(layer "B.Fab")
			(effects
				(font
					(size 1.27 1.27)
				)
				(justify mirror)
			)
		)
		(duplicate_pad_numbers_are_jumpers no)
		(fp_poly
			(pts
				(xy 0.2794 -0.1016) (xy -0.2794 -0.1016) (xy -0.2794 0.9906) (xy 0.2794 0.9906)
			)
			(stroke
				(width 0)
				(type default)
			)
			(fill no)
			(layer "B.CrtYd")
		)
		(fp_line
			(start -0.2794 -0.1016)
			(end 0.2794 -0.1016)
			(stroke
				(width 0.1)
				(type default)
			)
			(layer "B.Fab")
		)
		(fp_line
			(start -0.2794 0.9906)
			(end -0.2794 -0.1016)
			(stroke
				(width 0.1)
				(type default)
			)
			(layer "B.Fab")
		)
		(fp_line
			(start 0.2794 -0.1016)
			(end 0.2794 0.9906)
			(stroke
				(width 0.1)
				(type default)
			)
			(layer "B.Fab")
		)
		(fp_line
			(start 0.2794 0.9906)
			(end -0.2794 0.9906)
			(stroke
				(width 0.1)
				(type default)
			)
			(layer "B.Fab")
		)
		(pad "1" smd rect
			(at 0 0 180)
			(size 0.508 0.508)
			(layers "B.Cu" "B.Mask" "B.Paste")
			(net "CLK_100M_CPU1_BCLK0_DN")
		)
		(pad "2" smd rect
			(at 0 0.889 180)
			(size 0.508 0.508)
			(layers "B.Cu" "B.Mask" "B.Paste")
			(net "GND")
		)
		(zone
			(layer "B.Cu")
			(hatch none 0.5)
			(connect_pads
				(clearance 0)
			)
			(min_thickness 0.25)
			(keepout
				(tracks allowed)
				(vias not_allowed)
				(pads allowed)
				(copperpour not_allowed)
				(footprints allowed)
			)
			(placement
				(enabled no)
				(sheetname "")
			)
			(fill
				(thermal_gap 0.5)
				(thermal_bridge_width 0.5)
				(island_removal_mode 0)
			)
			(polygon
				(pts
					(xy 167.64 -87.503) (xy 167.132 -87.503) (xy 167.132 -87.122) (xy 167.64 -87.122)
				)
			)
		)
		(zone
			(layer "B.Cu")
			(hatch none 0.5)
			(connect_pads
				(clearance 0)
			)
			(min_thickness 0.25)
			(keepout
				(tracks not_allowed)
				(vias allowed)
				(pads allowed)
				(copperpour not_allowed)
				(footprints allowed)
			)
			(placement
				(enabled no)
				(sheetname "")
			)
			(fill
				(thermal_gap 0.5)
				(thermal_bridge_width 0.5)
				(island_removal_mode 0)
			)
			(polygon
				(pts
					(xy 167.64 -87.122) (xy 167.132 -87.122) (xy 167.132 -87.503) (xy 167.64 -87.503)
				)
			)
		)
	)
	(footprint ""
		(layer "B.Cu")
		(at 32.832802 -59.973464 90)
		(property "Reference" "C9R7"
			(at 0 0 90)
			(layer "B.SilkS")
			(hide yes)
			(effects
				(font
					(size 1.27 1.27)
				)
				(justify mirror)
			)
		)
		(property "Value" ""
			(at 0 0 90)
			(layer "B.Fab")
			(effects
				(font
					(size 1.27 1.27)
				)
				(justify mirror)
			)
		)
		(duplicate_pad_numbers_are_jumpers no)
		(fp_poly
			(pts
				(xy 0.7239 -0.2159) (xy -0.7239 -0.2159) (xy -0.7239 1.9939) (xy 0.7239 1.9939)
			)
			(stroke
				(width 0)
				(type default)
			)
			(fill no)
			(layer "B.CrtYd")
		)
		(fp_line
			(start 0.7239 -0.2159)
			(end 0.7239 1.9939)
			(stroke
				(width 0.1)
				(type default)
			)
			(layer "B.Fab")
		)
		(fp_line
			(start -0.7239 -0.2159)
			(end 0.7239 -0.2159)
			(stroke
				(width 0.1)
				(type default)
			)
			(layer "B.Fab")
		)
		(fp_line
			(start 0.7239 1.9939)
			(end -0.7239 1.9939)
			(stroke
				(width 0.1)
				(type default)
			)
			(layer "B.Fab")
		)
		(fp_line
			(start -0.7239 1.9939)
			(end -0.7239 -0.2159)
			(stroke
				(width 0.1)
				(type default)
			)
			(layer "B.Fab")
		)
		(pad "1" smd rect
			(at 0 0 270)
			(size 1.27 1.016)
			(layers "B.Cu" "B.Mask" "B.Paste")
			(net "VR_FET_SW_P12V_STBY_PVCCIN_CPU1")
		)
		(pad "2" smd rect
			(at 0 1.778 270)
			(size 1.27 1.016)
			(layers "B.Cu" "B.Mask" "B.Paste")
			(net "GND")
		)
		(zone
			(layer "B.Cu")
			(hatch none 0.5)
			(connect_pads
				(clearance 0)
			)
			(min_thickness 0.25)
			(keepout
				(tracks not_allowed)
				(vias allowed)
				(pads allowed)
				(copperpour not_allowed)
				(footprints allowed)
			)
			(placement
				(enabled no)
				(sheetname "")
			)
			(fill
				(thermal_gap 0.5)
				(thermal_bridge_width 0.5)
				(island_removal_mode 0)
			)
			(polygon
				(pts
					(xy 33.340802 -60.608464) (xy 33.340802 -59.338464) (xy 34.102802 -59.338464) (xy 34.102802 -60.608464)
				)
			)
		)
	)
)
